FILE_TYPE = CONNECTIVITY;
{Allegro Design Entry HDL 17.2-2016 S081 (4005846) 1/11/2022}
"PAGE_NUMBER" = 190;
0"NC";
1"GND\g";
2"GND\g";
3"GND\g";
4"GND\g";
5"GND\g";
6"GND\g";
7"GND\g";
8"GND\g";
9"GND\g";
10"GND\g";
11"SW_PVDDCR_SOC_P1_SW2";
12"SW_PVDDCR_SOC_P1_PH2";
13"SW_PVDDCR_SOC_P1_PH1";
14"SW_PVDDCR_SOC_P1_SW1";
15"GND\g";
16"P12V_STBY\g";
17"GND\g";
18"SW_PVDDCR_SOC_P1_BOOT1_RC";
19"GND\g";
20"PVDDCR_SOC_P1\g";
21"SW_PVDDCR_SOC_P1_BOOT2_RC";
22"IND_SOC_P1_CPL2";
23"IND_SOC_P1_CPL3";
24"SW_PVDDCR_SOC_P1_SW1_RC";
25"SW_PVDDCR_SOC_P1_BOOT1";
26"NC_PVDDCR_SOC_P1_GL2_1";
27"NC_PVDDCR_SOC_P1_GL1_1";
28"GND\g";
29"PVDDCR_SOC_P1_TEMP1";
30"PVDDCR_SOC_P1_IMON1";
31"PVDDCR_SOC_P1_PWM1";
32"NC_PVDDCR_SOC_P1_DNC1";
33"PVDDCR_SOC_P1_LSET1";
34"PVDDCR_SOC_P1_VCC1";
35"PVDDCR_CPU0_P1_VCCS";
36"PVDDCR_CPU0_P1_PVCC\g";
37"GND\g";
38"SW_PVDDCR_SOC_P1_BOOT2";
39"SW_PVDDCR_SOC_P1_SW2_RC";
40"NC_PVDDCR_SOC_P1_GL2_2";
41"NC_PVDDCR_SOC_P1_GL1_2";
42"GND\g";
43"PVDDCR_SOC_P1_VCC2";
44"PVDDCR_CPU0_P1_PVCC\g";
45"PVDDCR_SOC_P1_IMON2";
46"PVDDCR_SOC_P1_TEMP1";
47"PVDDCR_SOC_P1_PWM2";
48"PVDDCR_SOC_P1_LSET2";
49"NC_PVDDCR_SOC_P1_DNC2";
50"PVDDCR_CPU0_P1_VCCS";
51"SW_P12V_STBY_PVDDCR_SOC_P1_FLT\g";
52"GND\g";
53"IND_SOC_P1_CPL2";
54"PVDDCR_SOC_P1_VOS1";
55"PVDDCR_SOC_P1\g";
56"GND\g";
57"SW_P12V_STBY_PVDDCR_SOC_P1_FLT\g";
58"PVDDCR_SOC_P1\g";
59"PVDDCR_SOC_P1_VOS2";
%"VCC_CORE"
"1","(-3900,5850)","0","pure_quanta_power","I102";
;
HDL_POWER"SW_P12V_STBY_PVDDCR_SOC_P1_FLT"
CDS_LIB"pure_quanta_power";
"A"51;
%"VCC_CORE"
"1","(-1425,3325)","0","pure_quanta_power","I104";
;
HDL_POWER"PVDDCR_SOC_P1"
CDS_LIB"pure_quanta_power";
"A"55;
%"UNIVERSAL_GND"
"1","(-1425,2700)","0","pure_quanta_power","I105";
;
CDS_LIB"pure_quanta_power"
HDL_POWER"GND";
"A"56;
%"Q_CAPP"
"1","(-3425,5575)","0","pure_quanta","I106";
;
LOCATION"PC336"
$SEC"1"
CDS_SEC"1"
VOLTAGE"25V"
MATERIAL"OSCON"
PACK_TYPE"THLF"
PART_NUMBER"CC72204MD02"
TOLERANCE"20%"
VALUE"220UF"
CDS_LIB"pure_quanta";
"A"
$PN"1"51;
"B"
$PN"2"52;
%"Q_CAPP"
"1","(-1425,3050)","0","pure_quanta","I107";
;
LOCATION"PC343"
$SEC"1"
CDS_SEC"1"
TOLERANCE"20%"
VALUE"470UF"
MATERIAL"SPCAP"
PART_NUMBER"CH747LM8825"
VOLTAGE"2.5V"
PACK_TYPE"SMLF"
CDS_LIB"pure_quanta";
"A"
$PN"1"55;
"B"
$PN"2"56;
%"Q_CAP"
"1","(-5425,5575)","0","pure_quanta","I108";
;
LOCATION"PC323_1"
$SEC"1"
CDS_SEC"1"
MATERIAL"X7R"
TOLERANCE"10%"
VALUE"0.1UF"
PART_NUMBER"CH4104K1B00"
VOLTAGE"25V"
PACK_TYPE"0402"
CDS_LIB"pure_quanta";
"B"
$PN"2"52;
"A"
$PN"1"51;
%"Q_CAP"
"1","(-5350,2850)","0","pure_quanta","I109";
;
LOCATION"PC324_2"
$SEC"1"
CDS_SEC"1"
MATERIAL"X7R"
TOLERANCE"10%"
VALUE"0.1UF"
PART_NUMBER"CH4104K1B00"
VOLTAGE"25V"
PACK_TYPE"0402"
CDS_LIB"pure_quanta";
"B"
$PN"2"37;
"A"
$PN"1"57;
%"Q_CAP"
"1","(-7525,5075)","0","pure_quanta","I110";
;
LOCATION"PC319"
$SEC"1"
CDS_SEC"1"
MATERIAL"X6S"
TOLERANCE"10%"
VALUE"2.2UF"
PART_NUMBER"CH5222KEB01"
VOLTAGE"10V"
PACK_TYPE"C0402"
CDS_LIB"pure_quanta";
"B"
$PN"2"1;
"A"
$PN"1"34;
%"UNIVERSAL_GND"
"1","(-7525,4875)","0","pure_quanta_power","I111";
;
CDS_LIB"pure_quanta_power"
HDL_POWER"GND";
"A"1;
%"UNIVERSAL_GND"
"1","(-7175,5375)","0","pure_quanta_power","I112";
;
CDS_LIB"pure_quanta_power"
HDL_POWER"GND";
"A"2;
%"Q_RES"
"2","(-7525,5625)","0","pure_quanta","I113";
;
LOCATION"PR205"
$SEC"1"
CDS_SEC"1"
WATTAGE"1/16W"
MATERIAL"CHIP"
VALUE"2.2"
PART_NUMBER"CS-2202FB00"
PACK_TYPE"0402LF"
TOLERANCE"1%"
CDS_LIB"pure_quanta";
"A"
$PN"1"36;
"B"
$PN"2"34;
%"Q_CAP"
"1","(-7175,5650)","0","pure_quanta","I114";
;
LOCATION"PC321_SOP1_1"
$SEC"1"
CDS_SEC"1"
MATERIAL"X6S"
TOLERANCE"10%"
VALUE"2.2UF"
PART_NUMBER"CH5222KEB01"
VOLTAGE"10V"
PACK_TYPE"C0402"
CDS_LIB"pure_quanta";
"B"
$PN"2"2;
"A"
$PN"1"36;
%"VCC_CORE"
"1","(-7525,6025)","0","pure_quanta_power","I115";
;
HDL_POWER"PVDDCR_CPU0_P1_PVCC"
CDS_LIB"pure_quanta_power";
"A"36;
%"Q_CAP"
"1","(-7500,2300)","0","pure_quanta","I116";
;
LOCATION"PC320"
$SEC"1"
CDS_SEC"1"
MATERIAL"X6S"
TOLERANCE"10%"
VALUE"2.2UF"
PART_NUMBER"CH5222KEB01"
VOLTAGE"10V"
PACK_TYPE"C0402"
CDS_LIB"pure_quanta";
"B"
$PN"2"3;
"A"
$PN"1"43;
%"UNIVERSAL_GND"
"1","(-7500,2100)","0","pure_quanta_power","I117";
;
CDS_LIB"pure_quanta_power"
HDL_POWER"GND";
"A"3;
%"UNIVERSAL_GND"
"1","(-7150,2600)","0","pure_quanta_power","I118";
;
CDS_LIB"pure_quanta_power"
HDL_POWER"GND";
"A"4;
%"Q_RES"
"2","(-7500,2850)","0","pure_quanta","I119";
;
LOCATION"PR206"
$SEC"1"
CDS_SEC"1"
WATTAGE"1/16W"
MATERIAL"CHIP"
TOLERANCE"1%"
VALUE"2.2"
PART_NUMBER"CS-2202FB00"
PACK_TYPE"0402LF"
CDS_LIB"pure_quanta";
"A"
$PN"1"44;
"B"
$PN"2"43;
%"Q_CAP"
"1","(-7150,2875)","0","pure_quanta","I120";
;
LOCATION"PC322_SOP1_2"
$SEC"1"
CDS_SEC"1"
MATERIAL"X6S"
TOLERANCE"10%"
VALUE"2.2UF"
PART_NUMBER"CH5222KEB01"
VOLTAGE"10V"
PACK_TYPE"C0402"
CDS_LIB"pure_quanta";
"B"
$PN"2"4;
"A"
$PN"1"44;
%"VCC_CORE"
"1","(-7500,3250)","0","pure_quanta_power","I121";
;
HDL_POWER"PVDDCR_CPU0_P1_PVCC"
CDS_LIB"pure_quanta_power";
"A"44;
%"UNIVERSAL_GND"
"1","(-4675,3800)","0","pure_quanta_power","I123";
;
CDS_LIB"pure_quanta_power"
HDL_POWER"GND";
"A"5;
%"Q_RES"
"2","(-4675,4025)","0","pure_quanta","I124";
;
LOCATION"PR525"
$SEC"1"
CDS_SEC"1"
VALUE"1.5"
WATTAGE"1/8W"
MATERIAL"EMPTY"
TOLERANCE"1%"
PART_NUMBER"CS-1504FB00"
PACK_TYPE"0402LF"
CDS_LIB"pure_quanta";
"A"
$PN"1"24;
"B"
$PN"2"5;
%"Q_CAP"
"1","(-4675,4525)","0","pure_quanta","I125";
;
LOCATION"PC141"
$SEC"1"
CDS_SEC"1"
VALUE"560PF"
MATERIAL"EMPTY"
TOLERANCE"10%"
PART_NUMBER"CH1566K1B09"
VOLTAGE"50V"
PACK_TYPE"C0402"
CDS_LIB"pure_quanta";
"B"
$PN"2"24;
"A"
$PN"1"14;
%"UNIVERSAL_GND"
"1","(-4600,975)","0","pure_quanta_power","I126";
;
CDS_LIB"pure_quanta_power"
HDL_POWER"GND";
"A"6;
%"Q_RES"
"2","(-4600,1200)","0","pure_quanta","I127";
;
LOCATION"PR526"
$SEC"1"
CDS_SEC"1"
WATTAGE"1/8W"
MATERIAL"EMPTY"
TOLERANCE"1%"
VALUE"1.5"
PART_NUMBER"CS-1504FB00"
PACK_TYPE"0402LF"
CDS_LIB"pure_quanta";
"A"
$PN"1"39;
"B"
$PN"2"6;
%"Q_CAP"
"1","(-4600,1750)","0","pure_quanta","I128";
;
LOCATION"PC149"
$SEC"1"
CDS_SEC"1"
MATERIAL"EMPTY"
TOLERANCE"10%"
VALUE"560PF"
PART_NUMBER"CH1566K1B09"
VOLTAGE"50V"
PACK_TYPE"C0402"
CDS_LIB"pure_quanta";
"B"
$PN"2"39;
"A"
$PN"1"11;
%"Q_RES"
"2","(-850,4525)","0","pure_quanta","I129";
;
LOCATION"PR339"
$SEC"1"
CDS_SEC"1"
WATTAGE"1/16W"
MATERIAL"CHIP"
TOLERANCE"1%"
VALUE"1K"
PART_NUMBER"TMP_QCS21002FB24"
PACK_TYPE"0402LF"
CDS_LIB"pure_quanta";
"A"
$PN"1"58;
"B"
$PN"2"15;
%"Q_CAP"
"1","(-3825,5575)","0","pure_quanta","I130";
;
LOCATION"PC334_1"
$SEC"1"
CDS_SEC"1"
PART_NUMBER"CH6104KEA00"
TOLERANCE"10%"
VOLTAGE"25V"
VALUE"10UF"
MATERIAL"X6S"
PACK_TYPE"C0805"
CDS_LIB"pure_quanta";
"B"
$PN"2"52;
"A"
$PN"1"51;
%"Q_CAP"
"1","(-3700,2850)","0","pure_quanta","I131";
;
LOCATION"PC335_2"
$SEC"1"
CDS_SEC"1"
PART_NUMBER"CH6104KEA00"
MATERIAL"X6S"
TOLERANCE"10%"
VALUE"10UF"
VOLTAGE"25V"
PACK_TYPE"C0805"
CDS_LIB"pure_quanta";
"B"
$PN"2"37;
"A"
$PN"1"57;
%"UNIVERSAL_GND"
"1","(-2300,4350)","0","pure_quanta_power","I133";
;
CDS_LIB"pure_quanta_power"
HDL_POWER"GND";
"A"17;
%"Q_RES"
"1","(-7175,4425)","0","pure_quanta","I15";
;
LOCATION"PR207"
$SEC"1"
CDS_SEC"1"
WATTAGE"1/16W"
MATERIAL"EMPTY"
TOLERANCE"1%"
VALUE"8.87K"
PART_NUMBER"CS28872FB01"
PACK_TYPE"0402LF"
CDS_LIB"pure_quanta";
"B"
$PN"2"33;
"A"
$PN"1"10;
%"Q_RES"
"1","(-4775,5075)","0","pure_quanta","I19";
;
LOCATION"PR209"
$SEC"1"
CDS_SEC"1"
PACK_TYPE"0402LF"
TOLERANCE"1%"
MATERIAL"CHIP"
WATTAGE"1/16W"
VALUE"4.7"
PART_NUMBER"CS-4702FB19"
CDS_LIB"pure_quanta";
"B"
$PN"2"18;
"A"
$PN"1"25;
%"UNIVERSAL_GND"
"1","(-5450,4000)","0","pure_quanta_power","I2";
;
CDS_LIB"pure_quanta_power"
HDL_POWER"GND";
"A"28;
%"Q_RES"
"1","(-4200,3700)","0","pure_quanta","I22";
;
LOCATION"PR211"
$SEC"1"
CDS_SEC"1"
VALUE"0"
PART_NUMBER"CS00002JB38"
WATTAGE"1/16W"
MATERIAL"CHIP"
TOLERANCE"5%"
PACK_TYPE"0402LF"
CDS_LIB"pure_quanta";
"B"
$PN"2"58;
"A"
$PN"1"54;
%"Q_CAP"
"1","(-5100,5575)","0","pure_quanta","I23";
;
LOCATION"PC325_1"
$SEC"1"
CDS_SEC"1"
MATERIAL"X6S"
TOLERANCE"10%"
VALUE"1UF"
PART_NUMBER"CH5104KEB02"
VOLTAGE"25V"
PACK_TYPE"C0402"
CDS_LIB"pure_quanta";
"B"
$PN"2"52;
"A"
$PN"1"51;
%"Q_CAP"
"1","(-4775,5575)","0","pure_quanta","I24";
;
LOCATION"PC327_1"
$SEC"1"
CDS_SEC"1"
MATERIAL"X6S"
TOLERANCE"10%"
VALUE"10UF"
PART_NUMBER"CH6104KEA00"
VOLTAGE"25V"
PACK_TYPE"C0805"
CDS_LIB"pure_quanta";
"B"
$PN"2"52;
"A"
$PN"1"51;
%"Q_CAP"
"1","(-4450,5575)","0","pure_quanta","I25";
;
LOCATION"PC329_1"
$SEC"1"
CDS_SEC"1"
MATERIAL"X6S"
TOLERANCE"10%"
VALUE"10UF"
PART_NUMBER"CH6104KEA00"
VOLTAGE"25V"
PACK_TYPE"C0805"
CDS_LIB"pure_quanta";
"B"
$PN"2"52;
"A"
$PN"1"51;
%"Q_CAP"
"1","(-4150,5575)","0","pure_quanta","I26";
;
LOCATION"PC331_1"
$SEC"1"
CDS_SEC"1"
MATERIAL"X6S"
TOLERANCE"10%"
VALUE"10UF"
PART_NUMBER"CH6104KEA00"
VOLTAGE"25V"
PACK_TYPE"C0805"
CDS_LIB"pure_quanta";
"B"
$PN"2"52;
"A"
$PN"1"51;
%"Q_CAP"
"1","(-1950,4525)","0","pure_quanta","I29";
;
LOCATION"PC338"
$SEC"1"
CDS_SEC"1"
MATERIAL"X7R"
TOLERANCE"10%"
VALUE"0.1UF"
PART_NUMBER"CH4104K1B00"
VOLTAGE"25V"
PACK_TYPE"0402"
CDS_LIB"pure_quanta";
"B"
$PN"2"15;
"A"
$PN"1"58;
%"UNIVERSAL_GND"
"1","(-3900,5250)","0","pure_quanta_power","I31";
;
CDS_LIB"pure_quanta_power"
HDL_POWER"GND";
"A"52;
%"Q_INDUCTOR"
"1","(-3050,5775)","0","pure_quanta","I34";
;
LOCATION"PL37"
$SEC"1"
CDS_SEC"1"
MATERIAL"IND"
VALUE"50NH/86A"
PART_NUMBER"CVA50^0MZ09"
PACK_TYPE"SMLF"
NEEDS_NO_SIZE"TRUE"
CDS_LIB"pure_quanta";
"1"
$PN"1"51;
"2"
$PN"2"16;
%"VCC_CORE"
"1","(-2775,5850)","0","pure_quanta_power","I35";
;
HDL_POWER"P12V_STBY"
CDS_LIB"pure_quanta_power";
"A"16;
%"Q_CAP"
"1","(-1550,4550)","0","pure_quanta","I37";
;
LOCATION"PC341_1"
$SEC"1"
CDS_SEC"1"
MATERIAL"X6S"
TOLERANCE"20%"
VALUE"22UF"
PART_NUMBER"TMP_QCH622KMEA01"
VOLTAGE"4V"
PACK_TYPE"0805"
CDS_LIB"pure_quanta";
"B"
$PN"2"15;
"A"
$PN"1"58;
%"UNIVERSAL_GND"
"1","(-850,4150)","0","pure_quanta_power","I38";
;
CDS_LIB"pure_quanta_power"
HDL_POWER"GND";
"A"15;
%"Q_CAP"
"1","(-1125,4550)","0","pure_quanta","I39";
;
LOCATION"PC344_1"
$SEC"1"
CDS_SEC"1"
MATERIAL"X6S"
TOLERANCE"20%"
VALUE"22UF"
VOLTAGE"4V"
PACK_TYPE"0805"
CDS_LIB"pure_quanta"
PART_NUMBER"TMP_QCH622KMEA01";
"B"
$PN"2"15;
"A"
$PN"1"58;
%"Q_CAP"
"1","(-7850,4450)","0","pure_quanta","I4";
;
LOCATION"PC317_7"
$SEC"1"
CDS_SEC"1"
MATERIAL"X7R"
TOLERANCE"10%"
VALUE"0.1UF"
PART_NUMBER"CH4104K1B00"
VOLTAGE"25V"
PACK_TYPE"0402"
CDS_LIB"pure_quanta";
"B"
$PN"2"8;
"A"
$PN"1"35;
%"VCC_CORE"
"1","(-850,4850)","0","pure_quanta_power","I40";
;
HDL_POWER"PVDDCR_SOC_P1"
CDS_LIB"pure_quanta_power";
"A"58;
%"Q_INDUCTOR4P_14"
"1","(-3175,4600)","0","pure_quanta","I42";
;
LOCATION"PL35"
$SEC"1"
CDS_SEC"1"
PART_NUMBER"CV+15^0TZ04"
PART_TYPE"SMLF"
MATERIAL"IND"
VALUE"150NH"
CDS_LIB"pure_quanta"
NEEDS_NO_SIZE"TRUE";
"1"
$PN"1"14;
"4"
$PN"4"58;
"3"
$PN"3"17;
"2"
$PN"2"53;
%"Q_CAP"
"1","(-3925,4950)","0","pure_quanta","I43";
;
LOCATION"PC333"
$SEC"1"
CDS_SEC"1"
MATERIAL"X7R"
TOLERANCE"10%"
VALUE"0.22UF"
PART_NUMBER"CH4223K1B00"
VOLTAGE"16V"
PACK_TYPE"0402"
CDS_LIB"pure_quanta";
"B"
$PN"2"13;
"A"
$PN"1"18;
%"ISL99390FRZTR5935"
"1","(-6025,4725)","0","pure_quanta","I44";
;
LOCATION"PU30"
$SEC"1"
CDS_SEC"1"
PART_TYPE"SMLF"
MATERIAL"IC"
VALUE"ISL99390FRZ-TR5935"
PART_NUMBER"AL099390004"
CDS_LIB"pure_quanta"
CDS_LMAN_SYM_OUTLINE"-300,700,250,-650"
NEEDS_NO_SIZE"TRUE";
"PGND2"
$PN"7_9-20_24"28;
"GL2"
$PN"41"26;
"GL1"
$PN"6"27;
"DNC"
$PN"31"32;
"EN"
$PN"35"34;
"PGND3"
$PN"40"28;
"VOS"
$PN"1"54;
"VIN2"
$PN"30"51;
"PGND1"
$PN"5"28;
"SW"
$PN"10_19"14;
"LSET"
$PN"37"33;
"IOUT"
$PN"38"30;
"TOUT_FLT"
$PN"36"29;
"PVCC"
$PN"4"36;
"PHASE"
$PN"32"13;
"VIN1"
$PN"25_29"51;
"BOOT"
$PN"33"25;
"AGND"
$PN"2"28;
"VCC"
$PN"3"34;
"REFIN"
$PN"39"35;
"PWM"
$PN"34"31;
%"UNIVERSAL_GND"
"1","(-5425,1250)","0","pure_quanta_power","I46";
;
CDS_LIB"pure_quanta_power"
HDL_POWER"GND";
"A"42;
%"Q_CAP"
"1","(-7825,1675)","0","pure_quanta","I48";
;
LOCATION"PC318_8"
$SEC"1"
CDS_SEC"1"
MATERIAL"X7R"
TOLERANCE"10%"
VALUE"0.1UF"
PART_NUMBER"CH4104K1B00"
VOLTAGE"25V"
PACK_TYPE"0402"
CDS_LIB"pure_quanta";
"B"
$PN"2"7;
"A"
$PN"1"50;
%"UNIVERSAL_GND"
"1","(-7825,1400)","0","pure_quanta_power","I49";
;
CDS_LIB"pure_quanta_power"
HDL_POWER"GND";
"A"7;
%"UNIVERSAL_GND"
"1","(-7850,4175)","0","pure_quanta_power","I5";
;
CDS_LIB"pure_quanta_power"
HDL_POWER"GND";
"A"8;
%"UNIVERSAL_GND"
"1","(-7500,1475)","0","pure_quanta_power","I50";
;
CDS_LIB"pure_quanta_power"
HDL_POWER"GND";
"A"9;
%"Q_RES"
"1","(-7150,1650)","0","pure_quanta","I52";
;
LOCATION"PR208"
$SEC"1"
CDS_SEC"1"
WATTAGE"1/16W"
MATERIAL"EMPTY"
TOLERANCE"1%"
VALUE"8.87K"
PART_NUMBER"CS28872FB01"
PACK_TYPE"0402LF"
CDS_LIB"pure_quanta";
"B"
$PN"2"48;
"A"
$PN"1"9;
%"UNIVERSAL_GND"
"1","(-7525,4250)","0","pure_quanta_power","I6";
;
CDS_LIB"pure_quanta_power"
HDL_POWER"GND";
"A"10;
%"Q_RES"
"1","(-4675,2300)","0","pure_quanta","I63";
;
LOCATION"PR210"
$SEC"1"
CDS_SEC"1"
PACK_TYPE"0402LF"
TOLERANCE"1%"
MATERIAL"CHIP"
WATTAGE"1/16W"
VALUE"4.7"
PART_NUMBER"CS-4702FB19"
CDS_LIB"pure_quanta";
"B"
$PN"2"21;
"A"
$PN"1"38;
%"Q_RES"
"1","(-4250,775)","0","pure_quanta","I65";
;
LOCATION"PR212"
$SEC"1"
CDS_SEC"1"
VALUE"0"
WATTAGE"1/16W"
MATERIAL"CHIP"
TOLERANCE"5%"
PART_NUMBER"CS00002JB38"
PACK_TYPE"0402LF"
CDS_LIB"pure_quanta";
"B"
$PN"2"20;
"A"
$PN"1"59;
%"Q_CAP"
"1","(-3800,2175)","0","pure_quanta","I66";
;
LOCATION"PC334"
$SEC"1"
CDS_SEC"1"
MATERIAL"X7R"
TOLERANCE"10%"
VALUE"0.22UF"
PART_NUMBER"CH4223K1B00"
VOLTAGE"16V"
PACK_TYPE"0402"
CDS_LIB"pure_quanta";
"B"
$PN"2"12;
"A"
$PN"1"21;
%"Q_CAP"
"1","(-4975,2850)","0","pure_quanta","I67";
;
LOCATION"PC326_2"
$SEC"1"
CDS_SEC"1"
MATERIAL"X6S"
TOLERANCE"10%"
VALUE"1UF"
PART_NUMBER"CH5104KEB02"
VOLTAGE"25V"
PACK_TYPE"C0402"
CDS_LIB"pure_quanta";
"B"
$PN"2"37;
"A"
$PN"1"57;
%"Q_CAP"
"1","(-4650,2850)","0","pure_quanta","I68";
;
LOCATION"PC328_2"
$SEC"1"
CDS_SEC"1"
MATERIAL"X6S"
TOLERANCE"10%"
VALUE"10UF"
PART_NUMBER"CH6104KEA00"
VOLTAGE"25V"
PACK_TYPE"C0805"
CDS_LIB"pure_quanta";
"B"
$PN"2"37;
"A"
$PN"1"57;
%"Q_CAP"
"1","(-4325,2850)","0","pure_quanta","I69";
;
LOCATION"PC330_2"
$SEC"1"
CDS_SEC"1"
MATERIAL"X6S"
TOLERANCE"10%"
VALUE"10UF"
PART_NUMBER"CH6104KEA00"
VOLTAGE"25V"
PACK_TYPE"C0805"
CDS_LIB"pure_quanta";
"B"
$PN"2"37;
"A"
$PN"1"57;
%"Q_CAP"
"1","(-4025,2850)","0","pure_quanta","I70";
;
LOCATION"PC332_2"
$SEC"1"
CDS_SEC"1"
MATERIAL"X6S"
TOLERANCE"10%"
VALUE"10UF"
PART_NUMBER"CH6104KEA00"
VOLTAGE"25V"
PACK_TYPE"C0805"
CDS_LIB"pure_quanta";
"B"
$PN"2"37;
"A"
$PN"1"57;
%"UNIVERSAL_GND"
"1","(-3700,2525)","0","pure_quanta_power","I71";
;
CDS_LIB"pure_quanta_power"
HDL_POWER"GND";
"A"37;
%"VCC_CORE"
"1","(-3700,3150)","0","pure_quanta_power","I73";
;
HDL_POWER"SW_P12V_STBY_PVDDCR_SOC_P1_FLT"
CDS_LIB"pure_quanta_power";
"A"57;
%"Q_CAP"
"1","(-1675,1775)","0","pure_quanta","I79";
;
LOCATION"PC339_2"
$SEC"1"
CDS_SEC"1"
MATERIAL"X6S"
TOLERANCE"20%"
VALUE"22UF"
PART_NUMBER"TMP_QCH622KMEA01"
VOLTAGE"4V"
PACK_TYPE"0805"
CDS_LIB"pure_quanta";
"B"
$PN"2"19;
"A"
$PN"1"20;
%"UNIVERSAL_GND"
"1","(-1250,1425)","0","pure_quanta_power","I80";
;
CDS_LIB"pure_quanta_power"
HDL_POWER"GND";
"A"19;
%"Q_CAP"
"1","(-1250,1775)","0","pure_quanta","I81";
;
LOCATION"PC342_2"
$SEC"1"
CDS_SEC"1"
MATERIAL"X6S"
TOLERANCE"20%"
VALUE"22UF"
PART_NUMBER"TMP_QCH622KMEA01"
VOLTAGE"4V"
PACK_TYPE"0805"
CDS_LIB"pure_quanta";
"B"
$PN"2"19;
"A"
$PN"1"20;
%"VCC_CORE"
"1","(-1250,2100)","0","pure_quanta_power","I82";
;
HDL_POWER"PVDDCR_SOC_P1"
CDS_LIB"pure_quanta_power";
"A"20;
%"Q_INDUCTOR4P_14"
"1","(-2925,1825)","0","pure_quanta","I83";
;
LOCATION"PL36"
$SEC"1"
CDS_SEC"1"
VALUE"150NH"
PART_TYPE"SMLF"
MATERIAL"IND"
PART_NUMBER"CV+15^0TZ04"
CDS_LIB"pure_quanta"
NEEDS_NO_SIZE"TRUE";
"1"
$PN"1"11;
"4"
$PN"4"20;
"3"
$PN"3"22;
"2"
$PN"2"23;
%"ISL99390FRZTR5935"
"1","(-6000,1950)","0","pure_quanta","I84";
;
LOCATION"PU31"
$SEC"1"
CDS_SEC"1"
PART_TYPE"SMLF"
MATERIAL"IC"
VALUE"ISL99390FRZ-TR5935"
PART_NUMBER"AL099390004"
NEEDS_NO_SIZE"TRUE"
CDS_LMAN_SYM_OUTLINE"-300,700,250,-650"
CDS_LIB"pure_quanta";
"PGND2"
$PN"7_9-20_24"42;
"GL2"
$PN"41"40;
"GL1"
$PN"6"41;
"DNC"
$PN"31"49;
"EN"
$PN"35"43;
"PGND3"
$PN"40"42;
"VOS"
$PN"1"59;
"VIN2"
$PN"30"57;
"PGND1"
$PN"5"42;
"SW"
$PN"10_19"11;
"LSET"
$PN"37"48;
"IOUT"
$PN"38"45;
"TOUT_FLT"
$PN"36"46;
"PVCC"
$PN"4"44;
"PHASE"
$PN"32"12;
"VIN1"
$PN"25_29"57;
"BOOT"
$PN"33"38;
"AGND"
$PN"2"42;
"VCC"
$PN"3"43;
"REFIN"
$PN"39"50;
"PWM"
$PN"34"47;
%"Q_CAPP"
"1","(-2100,3050)","0","pure_quanta","I92";
;
LOCATION"PC337"
$SEC"1"
CDS_SEC"1"
PACK_TYPE"SMLF"
MATERIAL"SPCAP"
TOLERANCE"20%"
VALUE"470UF"
PART_NUMBER"CH747LM8825"
VOLTAGE"2.5V"
CDS_LIB"pure_quanta";
"A"
$PN"1"55;
"B"
$PN"2"56;
%"Q_CAPP"
"1","(-1750,3050)","0","pure_quanta","I94";
;
LOCATION"PC340"
$SEC"1"
CDS_SEC"1"
MATERIAL"EMPTY"
TOLERANCE"20%"
VALUE"470UF"
PART_NUMBER"CH747LM8825"
VOLTAGE"2.5V"
PACK_TYPE"SMLF"
CDS_LIB"pure_quanta";
"A"
$PN"1"55;
"B"
$PN"2"56;
END.
